(kicad_pcb
	(version 20241229)
	(generator "pcbnew")
	(generator_version "9.0")
	(general
		(thickness 1.711)
		(legacy_teardrops no)
	)
	(paper "A4")
	(title_block
		(title "Antmicro Baseboard for Jetson AGX Thor")
		(date "2026-02-18")
		(rev "1.1.0")
		(company "Antmicro Ltd")
		(comment 1 "www.antmicro.com")
		(comment 9 "footprints 154-158 of 1170")
	)
	(layers
		(0 "F.Cu" signal)
		(4 "In1.Cu" signal)
		(6 "In2.Cu" signal)
		(8 "In3.Cu" signal)
		(10 "In4.Cu" jumper)
		(12 "In5.Cu" signal)
		(14 "In6.Cu" signal)
		(16 "In7.Cu" signal)
		(18 "In8.Cu" signal)
		(2 "B.Cu" signal)
		(9 "F.Adhes" user "F.Adhesive")
		(11 "B.Adhes" user "B.Adhesive")
		(13 "F.Paste" user)
		(15 "B.Paste" user)
		(5 "F.SilkS" user "F.Silkscreen")
		(7 "B.SilkS" user "B.Silkscreen")
		(1 "F.Mask" user)
		(3 "B.Mask" user)
		(17 "Dwgs.User" user "User.Drawings")
		(19 "Cmts.User" user "User.Comments")
		(21 "Eco1.User" user "User.Eco1")
		(23 "Eco2.User" user "User.Eco2")
		(25 "Edge.Cuts" user)
		(27 "Margin" user)
		(31 "F.CrtYd" user "F.Courtyard")
		(29 "B.CrtYd" user "B.Courtyard")
		(35 "F.Fab" user)
		(33 "B.Fab" user)
	)
	(footprint "antmicro-footprints:R_0402_1005Metric"
		(layer "F.Cu")
		(at 147 110)
		(descr "Resistor SMD 0402")
		(tags "resistor SMD 0402")
		(property "Reference" "R228"
			(at -3.6 0.4 0)
			(layer "F.SilkS")
			(effects
				(font
					(size 0.7 0.7)
					(thickness 0.15)
				)
				(justify left bottom)
			)
		)
		(property "Value" "R_2k2_0402"
			(at -1.011843 1.772047 0)
			(layer "F.Fab")
			(effects
				(font
					(size 0.7 0.7)
					(thickness 0.15)
				)
				(justify left bottom)
			)
		)
		(property "Datasheet" "https://www.bourns.com/docs/product-datasheets/cr.pdf"
			(at 0 0 0)
			(layer "F.Fab")
			(hide yes)
			(effects
				(font
					(size 1.27 1.27)
					(thickness 0.15)
				)
			)
		)
		(property "Description" "SMD Chip Resistor, 2.2 kohm, ± 1%, 62.5 mW, 0402 [1005 Metric], Thick Film, General Purpose"
			(at 0 0 0)
			(layer "F.Fab")
			(hide yes)
			(effects
				(font
					(size 1.27 1.27)
					(thickness 0.15)
				)
			)
		)
		(property "MPN" "CR0402-FX-2201GLF"
			(at 0 0 0)
			(unlocked yes)
			(layer "F.Fab")
			(hide yes)
			(effects
				(font
					(size 1 1)
					(thickness 0.15)
				)
			)
		)
		(property "Manufacturer" "Bourns"
			(at 0 0 0)
			(unlocked yes)
			(layer "F.Fab")
			(hide yes)
			(effects
				(font
					(size 1 1)
					(thickness 0.15)
				)
			)
		)
		(property "License" "Apache-2.0"
			(at 0 0 0)
			(unlocked yes)
			(layer "F.Fab")
			(hide yes)
			(effects
				(font
					(size 1 1)
					(thickness 0.15)
				)
			)
		)
		(property "Author" "Antmicro"
			(at 0 0 0)
			(unlocked yes)
			(layer "F.Fab")
			(hide yes)
			(effects
				(font
					(size 1 1)
					(thickness 0.15)
				)
			)
		)
		(property "Val" "2k2"
			(at 0 0 0)
			(unlocked yes)
			(layer "F.Fab")
			(hide yes)
			(effects
				(font
					(size 1 1)
					(thickness 0.15)
				)
			)
		)
		(property "Tolerance" "1%"
			(at 0 0 0)
			(unlocked yes)
			(layer "F.Fab")
			(hide yes)
			(effects
				(font
					(size 1 1)
					(thickness 0.15)
				)
			)
		)
		(sheetname "/SoM_IO/")
		(sheetfile "som_io.kicad_sch")
		(attr smd exclude_from_pos_files exclude_from_bom dnp)
		(fp_rect
			(start -0.925 -0.47)
			(end 0.925 0.47)
			(stroke
				(width 0.05)
				(type default)
			)
			(fill no)
			(layer "F.CrtYd")
		)
		(fp_rect
			(start -0.5 -0.25)
			(end 0.5 0.25)
			(stroke
				(width 0.15)
				(type solid)
			)
			(fill no)
			(layer "F.Fab")
		)
		(fp_text user "${REFERENCE}"
			(at -0.95 3.168 0)
			(layer "F.Fab")
			(effects
				(font
					(size 0.7 0.7)
					(thickness 0.15)
				)
				(justify left bottom)
			)
		)
		(fp_text user "Author: Antmicro"
			(at -0.95 4.169 0)
			(layer "F.Fab")
			(effects
				(font
					(size 0.7 0.7)
					(thickness 0.15)
				)
				(justify left bottom)
			)
		)
		(fp_text user "License: Apache-2.0"
			(at -0.95 5.169 0)
			(layer "F.Fab")
			(effects
				(font
					(size 0.7 0.7)
					(thickness 0.15)
				)
				(justify left bottom)
			)
		)
		(pad "1" smd roundrect
			(at -0.48 0)
			(size 0.59 0.64)
			(layers "F.Cu" "F.Mask" "F.Paste")
			(roundrect_rratio 0.25)
			(net 11 "+1V8")
			(pintype "passive")
		)
		(pad "2" smd roundrect
			(at 0.48 0)
			(size 0.59 0.64)
			(layers "F.Cu" "F.Mask" "F.Paste")
			(roundrect_rratio 0.25)
			(net 139 "/SoM_IO/I2C2_SCL_1V8")
			(pintype "passive")
		)
	)
	(footprint "antmicro-footprints:C_0402_1005Metric"
		(layer "F.Cu")
		(at 91.1 97.3)
		(descr "Capacitor SMD 0402")
		(tags "capacitor SMD 0402")
		(property "Reference" "C349"
			(at 1.1 0.500001 0)
			(layer "F.SilkS")
			(effects
				(font
					(size 0.7 0.7)
					(thickness 0.15)
				)
				(justify left bottom)
			)
		)
		(property "Value" "C_100n_0402"
			(at -1.022927 2.155213 0)
			(layer "F.Fab")
			(effects
				(font
					(size 0.7 0.7)
					(thickness 0.15)
				)
				(justify left bottom)
			)
		)
		(property "Datasheet" "https://www.murata.com/products/productdetail?partno=GRM155R61H104KE14%23"
			(at 0 0 0)
			(layer "F.Fab")
			(hide yes)
			(effects
				(font
					(size 1.27 1.27)
					(thickness 0.15)
				)
			)
		)
		(property "Description" "SMD Multilayer Ceramic Capacitor, 0.1 µF, 50 V, 0402 [1005 Metric], ± 10%, X5R, GRM Series"
			(at 0 0 0)
			(layer "F.Fab")
			(hide yes)
			(effects
				(font
					(size 1.27 1.27)
					(thickness 0.15)
				)
			)
		)
		(property "Manufacturer" "Murata"
			(at 0 0 0)
			(unlocked yes)
			(layer "F.Fab")
			(hide yes)
			(effects
				(font
					(size 1 1)
					(thickness 0.15)
				)
			)
		)
		(property "MPN" "GRM155R61H104KE14D"
			(at 0 0 0)
			(unlocked yes)
			(layer "F.Fab")
			(hide yes)
			(effects
				(font
					(size 1 1)
					(thickness 0.15)
				)
			)
		)
		(property "Val" "100n"
			(at 0 0 0)
			(unlocked yes)
			(layer "F.Fab")
			(hide yes)
			(effects
				(font
					(size 1 1)
					(thickness 0.15)
				)
			)
		)
		(property "License" "Apache-2.0"
			(at 0 0 0)
			(unlocked yes)
			(layer "F.Fab")
			(hide yes)
			(effects
				(font
					(size 1 1)
					(thickness 0.15)
				)
			)
		)
		(property "Author" "Antmicro"
			(at 0 0 0)
			(unlocked yes)
			(layer "F.Fab")
			(hide yes)
			(effects
				(font
					(size 1 1)
					(thickness 0.15)
				)
			)
		)
		(property "Voltage" "50V"
			(at 0 0 0)
			(unlocked yes)
			(layer "F.Fab")
			(hide yes)
			(effects
				(font
					(size 1 1)
					(thickness 0.15)
				)
			)
		)
		(property "Dielectric" "X5R"
			(at 0 0 0)
			(unlocked yes)
			(layer "F.Fab")
			(hide yes)
			(effects
				(font
					(size 1 1)
					(thickness 0.15)
				)
			)
		)
		(sheetname "/SoM_IO2/")
		(sheetfile "som_io2.kicad_sch")
		(attr smd)
		(fp_rect
			(start -0.925 -0.47)
			(end 0.925 0.47)
			(stroke
				(width 0.05)
				(type default)
			)
			(fill no)
			(layer "F.CrtYd")
		)
		(fp_line
			(start -0.494 -0.25)
			(end 0.504 -0.25)
			(stroke
				(width 0.15)
				(type solid)
			)
			(layer "F.Fab")
		)
		(fp_line
			(start -0.494 0.248)
			(end -0.494 -0.25)
			(stroke
				(width 0.15)
				(type solid)
			)
			(layer "F.Fab")
		)
		(fp_line
			(start 0.504 -0.25)
			(end 0.504 0.248)
			(stroke
				(width 0.15)
				(type solid)
			)
			(layer "F.Fab")
		)
		(fp_line
			(start 0.504 0.248)
			(end -0.494 0.248)
			(stroke
				(width 0.15)
				(type solid)
			)
			(layer "F.Fab")
		)
		(fp_text user "Author: Antmicro"
			(at -0.939 3.399 0)
			(layer "F.Fab")
			(effects
				(font
					(size 0.7 0.7)
					(thickness 0.15)
				)
				(justify left bottom)
			)
		)
		(fp_text user "${REFERENCE}"
			(at -0.939 4.599 0)
			(layer "F.Fab")
			(effects
				(font
					(size 0.7 0.7)
					(thickness 0.15)
				)
				(justify left bottom)
			)
		)
		(fp_text user "License: Apache-2.0"
			(at -0.939 5.799 0)
			(layer "F.Fab")
			(effects
				(font
					(size 0.7 0.7)
					(thickness 0.15)
				)
				(justify left bottom)
			)
		)
		(pad "1" smd roundrect
			(at -0.48 0)
			(size 0.59 0.64)
			(layers "F.Cu" "F.Mask" "F.Paste")
			(roundrect_rratio 0.25)
			(net 675 "/Expansion connector/DP3.TX1-")
			(pintype "passive")
		)
		(pad "2" smd roundrect
			(at 0.48 0)
			(size 0.59 0.64)
			(layers "F.Cu" "F.Mask" "F.Paste")
			(roundrect_rratio 0.25)
			(net 1269 "/SoM_IO2/DP3.TX1_C-")
			(pintype "passive")
		)
	)
	(footprint "antmicro-footprints:QFN-2L_1.6x1x0.55mm"
		(layer "F.Cu")
		(at 160.6 93.8 90)
		(property "Reference" "D7"
			(at 0 -0.799999 90)
			(layer "F.SilkS")
			(effects
				(font
					(size 0.7 0.7)
					(thickness 0.15)
				)
				(justify left bottom)
			)
		)
		(property "Value" "ESDA25P35-1U1M"
			(at 0 1.700001 90)
			(layer "F.Fab")
			(effects
				(font
					(size 0.7 0.7)
					(thickness 0.15)
				)
				(justify left bottom)
			)
		)
		(property "Datasheet" "https://www.st.com/resource/en/datasheet/esda25p35-1u1m.pdf"
			(at 0 0 90)
			(layer "F.Fab")
			(hide yes)
			(effects
				(font
					(size 1.27 1.27)
					(thickness 0.15)
				)
			)
		)
		(property "Description" "Unidirectional TVS, 30 kV, QFN-2L, 22 V, 195 pF"
			(at 0 0 90)
			(layer "F.Fab")
			(hide yes)
			(effects
				(font
					(size 1.27 1.27)
					(thickness 0.15)
				)
			)
		)
		(property "Manufacturer" "STMicroelectronics"
			(at 0 0 90)
			(unlocked yes)
			(layer "F.Fab")
			(hide yes)
			(effects
				(font
					(size 1 1)
					(thickness 0.15)
				)
			)
		)
		(property "MPN" "ESDA25P35-1U1M"
			(at 0 0 90)
			(unlocked yes)
			(layer "F.Fab")
			(hide yes)
			(effects
				(font
					(size 1 1)
					(thickness 0.15)
				)
			)
		)
		(property "Author" "Antmicro"
			(at 0 0 90)
			(unlocked yes)
			(layer "F.Fab")
			(hide yes)
			(effects
				(font
					(size 1 1)
					(thickness 0.15)
				)
			)
		)
		(property "License" "Apache-2.0"
			(at 0 0 90)
			(unlocked yes)
			(layer "F.Fab")
			(hide yes)
			(effects
				(font
					(size 1 1)
					(thickness 0.15)
				)
			)
		)
		(component_classes
			(class "DCDC_SOM")
		)
		(sheetname "/DCDC/")
		(sheetfile "dcdc.kicad_sch")
		(attr smd)
		(fp_line
			(start 0.230001 -0.45)
			(end -0.230001 -0.45)
			(stroke
				(width 0.15)
				(type solid)
			)
			(layer "F.SilkS")
		)
		(fp_line
			(start -1.2 -0.4)
			(end -1.2 0.4)
			(stroke
				(width 0.15)
				(type solid)
			)
			(layer "F.SilkS")
		)
		(fp_line
			(start 0.230001 0.45)
			(end -0.230001 0.45)
			(stroke
				(width 0.15)
				(type solid)
			)
			(layer "F.SilkS")
		)
		(fp_poly
			(pts
				(xy 1.25 0.65) (xy 1.25 -0.65) (xy -1.25 -0.65) (xy -1.25 0.65)
			)
			(stroke
				(width 0.05)
				(type solid)
			)
			(fill no)
			(layer "F.CrtYd")
		)
		(fp_line
			(start 0.201 -0.202)
			(end -0.101 0)
			(stroke
				(width 0.15)
				(type solid)
			)
			(layer "F.Fab")
		)
		(fp_line
			(start -0.199 -0.202)
			(end -0.199 0.1)
			(stroke
				(width 0.15)
				(type solid)
			)
			(layer "F.Fab")
		)
		(fp_line
			(start 0.599 0)
			(end 0.200999 0)
			(stroke
				(width 0.15)
				(type solid)
			)
			(layer "F.Fab")
		)
		(fp_line
			(start 0.200999 0)
			(end 0.201 -0.202)
			(stroke
				(width 0.15)
				(type solid)
			)
			(layer "F.Fab")
		)
		(fp_line
			(start -0.101 0)
			(end 0.201 0.2)
			(stroke
				(width 0.15)
				(type solid)
			)
			(layer "F.Fab")
		)
		(fp_line
			(start -0.199 0)
			(end -0.597 0)
			(stroke
				(width 0.15)
				(type solid)
			)
			(layer "F.Fab")
		)
		(fp_line
			(start 0.201 0.2)
			(end 0.200999 0)
			(stroke
				(width 0.15)
				(type solid)
			)
			(layer "F.Fab")
		)
		(fp_line
			(start -0.199 0.2)
			(end -0.199 0.1)
			(stroke
				(width 0.15)
				(type solid)
			)
			(layer "F.Fab")
		)
		(fp_poly
			(pts
				(xy 0.848 0.4) (xy 0.848 -0.401999) (xy -0.85 -0.402) (xy -0.85 0.4)
			)
			(stroke
				(width 0.15)
				(type solid)
			)
			(fill no)
			(layer "F.Fab")
		)
		(fp_text user "License: Apache-2.0"
			(at -1.31 5.769 90)
			(layer "F.Fab")
			(effects
				(font
					(size 0.7 0.7)
					(thickness 0.15)
				)
				(justify left bottom)
			)
		)
		(fp_text user "${REFERENCE}"
			(at -1.309999 3.769 90)
			(layer "F.Fab")
			(effects
				(font
					(size 0.7 0.7)
					(thickness 0.15)
				)
				(justify left bottom)
			)
		)
		(fp_text user "Author: Antmicro"
			(at -1.31 4.769 90)
			(layer "F.Fab")
			(effects
				(font
					(size 0.7 0.7)
					(thickness 0.15)
				)
				(justify left bottom)
			)
		)
		(pad "1" smd roundrect
			(at -0.7 0 270)
			(size 0.8 1)
			(layers "F.Cu" "F.Mask" "F.Paste")
			(roundrect_rratio 0.2)
			(net 12 "SYS_VIN_HV")
			(pinfunction "C")
			(pintype "passive")
		)
		(pad "2" smd roundrect
			(at 0.7 0 270)
			(size 0.8 1)
			(layers "F.Cu" "F.Mask" "F.Paste")
			(roundrect_rratio 0.2)
			(net 1 "GND")
			(pinfunction "A")
			(pintype "passive")
		)
	)
	(footprint "antmicro-footprints:C_0603_1608Metric_EIA"
		(layer "F.Cu")
		(at 188.25 127.3 -90)
		(descr "Capacitor SMD 0603, IPC-7351 Density Level A")
		(tags "Capacitor 0603")
		(property "Reference" "C35"
			(at 1.1 0.45 90)
			(layer "F.SilkS")
			(effects
				(font
					(size 0.7 0.7)
					(thickness 0.15)
				)
				(justify right top)
			)
		)
		(property "Value" "C_22u_16V_0603"
			(at -1.42757 1.770288 90)
			(layer "F.Fab")
			(effects
				(font
					(size 0.7 0.7)
					(thickness 0.15)
				)
				(justify right top)
			)
		)
		(property "Datasheet" "https://product.samsungsem.com/mlcc/CL10A226MO7JZN.do"
			(at 0 0 90)
			(layer "F.Fab")
			(hide yes)
			(effects
				(font
					(size 1.27 1.27)
					(thickness 0.15)
				)
			)
		)
		(property "Description" "SMD Multilayer Ceramic Capacitor"
			(at 0 0 90)
			(layer "F.Fab")
			(hide yes)
			(effects
				(font
					(size 1.27 1.27)
					(thickness 0.15)
				)
			)
		)
		(property "MPN" "CL10A226MO7JZNC"
			(at 0 0 270)
			(unlocked yes)
			(layer "F.Fab")
			(hide yes)
			(effects
				(font
					(size 1 1)
					(thickness 0.15)
				)
			)
		)
		(property "Manufacturer" "Samsung Electro-Mechanics"
			(at 0 0 270)
			(unlocked yes)
			(layer "F.Fab")
			(hide yes)
			(effects
				(font
					(size 1 1)
					(thickness 0.15)
				)
			)
		)
		(property "License" "Apache-2.0"
			(at 0 0 270)
			(unlocked yes)
			(layer "F.Fab")
			(hide yes)
			(effects
				(font
					(size 1 1)
					(thickness 0.15)
				)
			)
		)
		(property "Author" "Antmicro"
			(at 0 0 270)
			(unlocked yes)
			(layer "F.Fab")
			(hide yes)
			(effects
				(font
					(size 1 1)
					(thickness 0.15)
				)
			)
		)
		(property "Val" "22u"
			(at 0 0 270)
			(unlocked yes)
			(layer "F.Fab")
			(hide yes)
			(effects
				(font
					(size 1 1)
					(thickness 0.15)
				)
			)
		)
		(property "Voltage" "16V"
			(at 0 0 270)
			(unlocked yes)
			(layer "F.Fab")
			(hide yes)
			(effects
				(font
					(size 1 1)
					(thickness 0.15)
				)
			)
		)
		(property "Dielectric" ""
			(at 0 0 270)
			(unlocked yes)
			(layer "F.Fab")
			(hide yes)
			(effects
				(font
					(size 1 1)
					(thickness 0.15)
				)
			)
		)
		(property "Public" "False"
			(at 0 0 270)
			(unlocked yes)
			(layer "F.Fab")
			(hide yes)
			(effects
				(font
					(size 1 1)
					(thickness 0.15)
				)
			)
		)
		(component_classes
			(class "DCDC_1V15")
		)
		(sheetname "/DCDC/")
		(sheetfile "dcdc.kicad_sch")
		(attr smd)
		(fp_line
			(start -0.15 0.55)
			(end 0.15 0.55)
			(stroke
				(width 0.15)
				(type solid)
			)
			(layer "F.SilkS")
		)
		(fp_line
			(start -0.15 -0.55)
			(end 0.15 -0.55)
			(stroke
				(width 0.15)
				(type solid)
			)
			(layer "F.SilkS")
		)
		(fp_rect
			(start -1.25 -0.65)
			(end 1.25 0.65)
			(stroke
				(width 0.05)
				(type solid)
			)
			(fill no)
			(layer "F.CrtYd")
		)
		(fp_rect
			(start -0.8 -0.45)
			(end 0.8 0.45)
			(stroke
				(width 0.15)
				(type solid)
			)
			(fill no)
			(layer "F.Fab")
		)
		(fp_text user "${REFERENCE}"
			(at -1.682 3.895 90)
			(layer "F.Fab")
			(effects
				(font
					(size 0.7 0.7)
					(thickness 0.15)
				)
				(justify right top)
			)
		)
		(fp_text user "License: Apache-2.0"
			(at -1.682 5.895 90)
			(layer "F.Fab")
			(effects
				(font
					(size 0.7 0.7)
					(thickness 0.15)
				)
				(justify right top)
			)
		)
		(fp_text user "Author: Antmicro"
			(at -1.682 4.894 90)
			(layer "F.Fab")
			(effects
				(font
					(size 0.7 0.7)
					(thickness 0.15)
				)
				(justify right top)
			)
		)
		(pad "1" smd roundrect
			(at -0.7 0 270)
			(size 0.8 1.1)
			(layers "F.Cu" "F.Mask" "F.Paste")
			(roundrect_rratio 0.2)
			(net 1 "GND")
			(pintype "passive")
		)
		(pad "2" smd roundrect
			(at 0.7 0 270)
			(size 0.8 1.1)
			(layers "F.Cu" "F.Mask" "F.Paste")
			(roundrect_rratio 0.2)
			(net 5 "+5V")
			(pintype "passive")
		)
	)
	(footprint "antmicro-footprints:R_0402_1005Metric"
		(layer "F.Cu")
		(at 147 111)
		(descr "Resistor SMD 0402")
		(tags "resistor SMD 0402")
		(property "Reference" "R352"
			(at -3.6 0.4 0)
			(layer "F.SilkS")
			(effects
				(font
					(size 0.7 0.7)
					(thickness 0.15)
				)
				(justify left bottom)
			)
		)
		(property "Value" "R_2k2_0402"
			(at -1.011843 1.772047 0)
			(layer "F.Fab")
			(effects
				(font
					(size 0.7 0.7)
					(thickness 0.15)
				)
				(justify left bottom)
			)
		)
		(property "Datasheet" "https://www.bourns.com/docs/product-datasheets/cr.pdf"
			(at 0 0 0)
			(layer "F.Fab")
			(hide yes)
			(effects
				(font
					(size 1.27 1.27)
					(thickness 0.15)
				)
			)
		)
		(property "Description" "SMD Chip Resistor, 2.2 kohm, ± 1%, 62.5 mW, 0402 [1005 Metric], Thick Film, General Purpose"
			(at 0 0 0)
			(layer "F.Fab")
			(hide yes)
			(effects
				(font
					(size 1.27 1.27)
					(thickness 0.15)
				)
			)
		)
		(property "MPN" "CR0402-FX-2201GLF"
			(at 0 0 0)
			(unlocked yes)
			(layer "F.Fab")
			(hide yes)
			(effects
				(font
					(size 1 1)
					(thickness 0.15)
				)
			)
		)
		(property "Manufacturer" "Bourns"
			(at 0 0 0)
			(unlocked yes)
			(layer "F.Fab")
			(hide yes)
			(effects
				(font
					(size 1 1)
					(thickness 0.15)
				)
			)
		)
		(property "License" "Apache-2.0"
			(at 0 0 0)
			(unlocked yes)
			(layer "F.Fab")
			(hide yes)
			(effects
				(font
					(size 1 1)
					(thickness 0.15)
				)
			)
		)
		(property "Author" "Antmicro"
			(at 0 0 0)
			(unlocked yes)
			(layer "F.Fab")
			(hide yes)
			(effects
				(font
					(size 1 1)
					(thickness 0.15)
				)
			)
		)
		(property "Val" "2k2"
			(at 0 0 0)
			(unlocked yes)
			(layer "F.Fab")
			(hide yes)
			(effects
				(font
					(size 1 1)
					(thickness 0.15)
				)
			)
		)
		(property "Tolerance" "1%"
			(at 0 0 0)
			(unlocked yes)
			(layer "F.Fab")
			(hide yes)
			(effects
				(font
					(size 1 1)
					(thickness 0.15)
				)
			)
		)
		(sheetname "/SoM_IO/")
		(sheetfile "som_io.kicad_sch")
		(attr smd exclude_from_pos_files exclude_from_bom dnp)
		(fp_rect
			(start -0.925 -0.47)
			(end 0.925 0.47)
			(stroke
				(width 0.05)
				(type default)
			)
			(fill no)
			(layer "F.CrtYd")
		)
		(fp_rect
			(start -0.5 -0.25)
			(end 0.5 0.25)
			(stroke
				(width 0.15)
				(type solid)
			)
			(fill no)
			(layer "F.Fab")
		)
		(fp_text user "Author: Antmicro"
			(at -0.95 4.169 0)
			(layer "F.Fab")
			(effects
				(font
					(size 0.7 0.7)
					(thickness 0.15)
				)
				(justify left bottom)
			)
		)
		(fp_text user "License: Apache-2.0"
			(at -0.95 5.169 0)
			(layer "F.Fab")
			(effects
				(font
					(size 0.7 0.7)
					(thickness 0.15)
				)
				(justify left bottom)
			)
		)
		(fp_text user "${REFERENCE}"
			(at -0.95 3.168 0)
			(layer "F.Fab")
			(effects
				(font
					(size 0.7 0.7)
					(thickness 0.15)
				)
				(justify left bottom)
			)
		)
		(pad "1" smd roundrect
			(at -0.48 0)
			(size 0.59 0.64)
			(layers "F.Cu" "F.Mask" "F.Paste")
			(roundrect_rratio 0.25)
			(net 11 "+1V8")
			(pintype "passive")
		)
		(pad "2" smd roundrect
			(at 0.48 0)
			(size 0.59 0.64)
			(layers "F.Cu" "F.Mask" "F.Paste")
			(roundrect_rratio 0.25)
			(net 167 "/SoM_IO/I2C2_SDA_1V8")
			(pintype "passive")
		)
	)
)
